(kicad_pcb
	(version 20260206)
	(generator "pcbnew")
	(generator_version "10.0")
	(general
		(thickness 1.6)
		(legacy_teardrops no)
	)
	(paper "A4")
	(title_block
		(title "03242023_DA0F0TMBIJ0_F0T_Motherboard_J_brd_V01_OCP.brd")
		(comment 1 "Grand Teton / footprints 5570-5576 of 6105")
	)
	(layers
		(0 "F.Cu" signal "TOP")
		(4 "In1.Cu" signal "GND")
		(6 "In2.Cu" signal "IN1")
		(8 "In3.Cu" signal "GND1")
		(10 "In4.Cu" signal "IN2")
		(12 "In5.Cu" signal "GND2")
		(14 "In6.Cu" signal "IN3")
		(16 "In7.Cu" signal "GND3")
		(18 "In8.Cu" signal "VCC")
		(20 "In9.Cu" signal "VCC1")
		(22 "In10.Cu" signal "GND4")
		(24 "In11.Cu" signal "IN4")
		(26 "In12.Cu" signal "GND5")
		(28 "In13.Cu" signal "IN5")
		(30 "In14.Cu" signal "GND6")
		(32 "In15.Cu" signal "IN6")
		(34 "In16.Cu" signal "GND7")
		(2 "B.Cu" signal "BOTTOM")
		(9 "F.Adhes" user "F.Adhesive")
		(11 "B.Adhes" user "B.Adhesive")
		(13 "F.Paste" user "Package Geometry/Pastemask Top")
		(15 "B.Paste" user "Package Geometry/Pastemask Bottom")
		(5 "F.SilkS" user "Ref Des/Silkscreen Top")
		(7 "B.SilkS" user "Ref Des/Silkscreen Bottom")
		(1 "F.Mask" user "Board Geometry/Soldermask Top")
		(3 "B.Mask" user "Board Geometry/Soldermask Bottom")
		(17 "Dwgs.User" user "User.Drawings")
		(19 "Cmts.User" user "User.Comments")
		(21 "Eco1.User" user "User.Eco1")
		(23 "Eco2.User" user "User.Eco2")
		(25 "Edge.Cuts" user "Board Geometry/Outline")
		(27 "Margin" user)
		(31 "F.CrtYd" user "Package Geometry/Place Bound Top")
		(29 "B.CrtYd" user "Package Geometry/Place Bound Bottom")
		(35 "F.Fab" user "Ref Des/Assembly Top")
		(33 "B.Fab" user "Ref Des/Assembly Bottom")
	)
	(footprint ""
		(layer "B.Cu")
		(at 121.773442 -356.200456 180)
		(property "Reference" "R2367"
			(at 0 0 0)
			(layer "B.SilkS")
			(hide yes)
			(effects
				(font
					(size 1.27 1.27)
				)
				(justify mirror)
			)
		)
		(property "Value" ""
			(at 0 0 0)
			(layer "B.Fab")
			(effects
				(font
					(size 1.27 1.27)
				)
				(justify mirror)
			)
		)
		(duplicate_pad_numbers_are_jumpers no)
		(fp_line
			(start 0.7874 0.4064)
			(end 0.7874 -0.4064)
			(stroke
				(width 0.1524)
				(type default)
			)
			(layer "B.SilkS")
		)
		(fp_line
			(start 0.7874 -0.4064)
			(end -0.7874 -0.4064)
			(stroke
				(width 0.1524)
				(type default)
			)
			(layer "B.SilkS")
		)
		(fp_line
			(start -0.7874 0.4064)
			(end 0.7874 0.4064)
			(stroke
				(width 0.1524)
				(type default)
			)
			(layer "B.SilkS")
		)
		(fp_line
			(start -0.7874 -0.4064)
			(end -0.7874 0.4064)
			(stroke
				(width 0.1524)
				(type default)
			)
			(layer "B.SilkS")
		)
		(fp_line
			(start 0.67945 0.3048)
			(end 0.67945 -0.305054)
			(stroke
				(width 0.1)
				(type default)
			)
			(layer "B.Fab")
		)
		(fp_line
			(start 0.67945 -0.305054)
			(end 0.12065 -0.305054)
			(stroke
				(width 0.1)
				(type default)
			)
			(layer "B.Fab")
		)
		(fp_line
			(start 0.12065 0.3048)
			(end 0.67945 0.3048)
			(stroke
				(width 0.1)
				(type default)
			)
			(layer "B.Fab")
		)
		(fp_line
			(start 0.12065 0.2794)
			(end 0.12065 0.3048)
			(stroke
				(width 0.1)
				(type default)
			)
			(layer "B.Fab")
		)
		(fp_line
			(start 0.12065 -0.2794)
			(end -0.12065 -0.2794)
			(stroke
				(width 0.1)
				(type default)
			)
			(layer "B.Fab")
		)
		(fp_line
			(start 0.12065 -0.305054)
			(end 0.12065 -0.2794)
			(stroke
				(width 0.1)
				(type default)
			)
			(layer "B.Fab")
		)
		(fp_line
			(start -0.120396 0.3048)
			(end -0.120396 0.2794)
			(stroke
				(width 0.1)
				(type default)
			)
			(layer "B.Fab")
		)
		(fp_line
			(start -0.120396 0.2794)
			(end 0.12065 0.2794)
			(stroke
				(width 0.1)
				(type default)
			)
			(layer "B.Fab")
		)
		(fp_line
			(start -0.12065 -0.2794)
			(end -0.12065 -0.3048)
			(stroke
				(width 0.1)
				(type default)
			)
			(layer "B.Fab")
		)
		(fp_line
			(start -0.12065 -0.3048)
			(end -0.67945 -0.3048)
			(stroke
				(width 0.1)
				(type default)
			)
			(layer "B.Fab")
		)
		(fp_line
			(start -0.67945 0.3048)
			(end -0.120396 0.3048)
			(stroke
				(width 0.1)
				(type default)
			)
			(layer "B.Fab")
		)
		(fp_line
			(start -0.67945 -0.3048)
			(end -0.67945 0.3048)
			(stroke
				(width 0.1)
				(type default)
			)
			(layer "B.Fab")
		)
		(pad "1" smd circle
			(at 0.40005 0)
			(size 0 0)
			(layers "B.Cu" "B.Mask" "B.Paste")
			(net "P3V3_AUX")
		)
		(pad "2" smd circle
			(at -0.40005 0)
			(size 0 0)
			(layers "B.Cu" "B.Mask" "B.Paste")
			(net "FM_PVPP_HBM_CPU1_EN")
		)
	)
	(footprint ""
		(layer "B.Cu")
		(at 178.9557 -115.775486 90)
		(property "Reference" "C1918"
			(at 0 0 90)
			(layer "B.SilkS")
			(hide yes)
			(effects
				(font
					(size 1.27 1.27)
				)
				(justify mirror)
			)
		)
		(property "Value" ""
			(at 0 0 90)
			(layer "B.Fab")
			(effects
				(font
					(size 1.27 1.27)
				)
				(justify mirror)
			)
		)
		(duplicate_pad_numbers_are_jumpers no)
		(fp_line
			(start 0.69215 -0.2921)
			(end -0.69215 -0.2921)
			(stroke
				(width 0.1524)
				(type default)
			)
			(layer "B.SilkS")
		)
		(fp_line
			(start -0.69215 -0.2921)
			(end -0.69215 0.2921)
			(stroke
				(width 0.1524)
				(type default)
			)
			(layer "B.SilkS")
		)
		(fp_line
			(start 0.69215 0.2921)
			(end 0.69215 -0.2921)
			(stroke
				(width 0.1524)
				(type default)
			)
			(layer "B.SilkS")
		)
		(fp_line
			(start -0.69215 0.2921)
			(end 0.69215 0.2921)
			(stroke
				(width 0.1524)
				(type default)
			)
			(layer "B.SilkS")
		)
		(fp_line
			(start 0.51435 -0.2794)
			(end -0.51435 -0.2794)
			(stroke
				(width 0.1)
				(type default)
			)
			(layer "B.Fab")
		)
		(fp_line
			(start -0.51435 -0.2794)
			(end -0.51435 0.2794)
			(stroke
				(width 0.1)
				(type default)
			)
			(layer "B.Fab")
		)
		(fp_line
			(start 0.51435 0.2794)
			(end 0.51435 -0.2794)
			(stroke
				(width 0.1)
				(type default)
			)
			(layer "B.Fab")
		)
		(fp_line
			(start -0.51435 0.2794)
			(end 0.51435 0.2794)
			(stroke
				(width 0.1)
				(type default)
			)
			(layer "B.Fab")
		)
		(pad "1" smd circle
			(at 0.40005 0 270)
			(size 0 0)
			(layers "B.Cu" "B.Mask" "B.Paste")
			(net "P3V3_AUX_FPGA_VCCIO1")
		)
		(pad "2" smd circle
			(at -0.40005 0 270)
			(size 0 0)
			(layers "B.Cu" "B.Mask" "B.Paste")
			(net "GND")
		)
		(zone
			(layer "B.Cu")
			(hatch none 0.5)
			(connect_pads
				(clearance 0)
			)
			(min_thickness 0.25)
			(keepout
				(tracks not_allowed)
				(vias allowed)
				(pads allowed)
				(copperpour not_allowed)
				(footprints allowed)
			)
			(placement
				(enabled no)
				(sheetname "")
			)
			(fill
				(thermal_gap 0.5)
				(thermal_bridge_width 0.5)
				(island_removal_mode 0)
			)
			(polygon
				(pts
					(xy 179.04333 -115.965986) (xy 179.101496 -115.874546) (xy 179.101496 -115.675156) (xy 179.04333 -115.584986)
					(xy 178.86807 -115.584986) (xy 178.80965 -115.675156) (xy 178.80965 -115.874546) (xy 178.867816 -115.965986)
				)
			)
		)
	)
	(footprint ""
		(layer "B.Cu")
		(at 203.047346 -77.009752)
		(property "Reference" "R3209"
			(at 0 0 0)
			(layer "B.SilkS")
			(hide yes)
			(effects
				(font
					(size 1.27 1.27)
				)
				(justify mirror)
			)
		)
		(property "Value" ""
			(at 0 0 0)
			(layer "B.Fab")
			(effects
				(font
					(size 1.27 1.27)
				)
				(justify mirror)
			)
		)
		(duplicate_pad_numbers_are_jumpers no)
		(fp_line
			(start -0.7874 -0.4064)
			(end -0.7874 0.4064)
			(stroke
				(width 0.1524)
				(type default)
			)
			(layer "B.SilkS")
		)
		(fp_line
			(start -0.7874 0.4064)
			(end 0.7874 0.4064)
			(stroke
				(width 0.1524)
				(type default)
			)
			(layer "B.SilkS")
		)
		(fp_line
			(start 0.7874 -0.4064)
			(end -0.7874 -0.4064)
			(stroke
				(width 0.1524)
				(type default)
			)
			(layer "B.SilkS")
		)
		(fp_line
			(start 0.7874 0.4064)
			(end 0.7874 -0.4064)
			(stroke
				(width 0.1524)
				(type default)
			)
			(layer "B.SilkS")
		)
		(fp_line
			(start -0.67945 -0.3048)
			(end -0.67945 0.3048)
			(stroke
				(width 0.1)
				(type default)
			)
			(layer "B.Fab")
		)
		(fp_line
			(start -0.67945 0.3048)
			(end -0.120396 0.3048)
			(stroke
				(width 0.1)
				(type default)
			)
			(layer "B.Fab")
		)
		(fp_line
			(start -0.12065 -0.3048)
			(end -0.67945 -0.3048)
			(stroke
				(width 0.1)
				(type default)
			)
			(layer "B.Fab")
		)
		(fp_line
			(start -0.12065 -0.2794)
			(end -0.12065 -0.3048)
			(stroke
				(width 0.1)
				(type default)
			)
			(layer "B.Fab")
		)
		(fp_line
			(start -0.120396 0.2794)
			(end 0.12065 0.2794)
			(stroke
				(width 0.1)
				(type default)
			)
			(layer "B.Fab")
		)
		(fp_line
			(start -0.120396 0.3048)
			(end -0.120396 0.2794)
			(stroke
				(width 0.1)
				(type default)
			)
			(layer "B.Fab")
		)
		(fp_line
			(start 0.12065 -0.305054)
			(end 0.12065 -0.2794)
			(stroke
				(width 0.1)
				(type default)
			)
			(layer "B.Fab")
		)
		(fp_line
			(start 0.12065 -0.2794)
			(end -0.12065 -0.2794)
			(stroke
				(width 0.1)
				(type default)
			)
			(layer "B.Fab")
		)
		(fp_line
			(start 0.12065 0.2794)
			(end 0.12065 0.3048)
			(stroke
				(width 0.1)
				(type default)
			)
			(layer "B.Fab")
		)
		(fp_line
			(start 0.12065 0.3048)
			(end 0.67945 0.3048)
			(stroke
				(width 0.1)
				(type default)
			)
			(layer "B.Fab")
		)
		(fp_line
			(start 0.67945 -0.305054)
			(end 0.12065 -0.305054)
			(stroke
				(width 0.1)
				(type default)
			)
			(layer "B.Fab")
		)
		(fp_line
			(start 0.67945 0.3048)
			(end 0.67945 -0.305054)
			(stroke
				(width 0.1)
				(type default)
			)
			(layer "B.Fab")
		)
		(pad "1" smd circle
			(at 0.40005 0 180)
			(size 0 0)
			(layers "B.Cu" "B.Mask" "B.Paste")
			(net "OCP_V3_2_RBT_ARB_IN_R")
		)
		(pad "2" smd circle
			(at -0.40005 0 180)
			(size 0 0)
			(layers "B.Cu" "B.Mask" "B.Paste")
			(net "OCP_V3_2_RBT_ARB_IN")
		)
	)
	(footprint ""
		(layer "B.Cu")
		(at 15.69085 -316.601094 90)
		(property "Reference" "R3898"
			(at 0 0 90)
			(layer "B.SilkS")
			(hide yes)
			(effects
				(font
					(size 1.27 1.27)
				)
				(justify mirror)
			)
		)
		(property "Value" ""
			(at 0 0 90)
			(layer "B.Fab")
			(effects
				(font
					(size 1.27 1.27)
				)
				(justify mirror)
			)
		)
		(duplicate_pad_numbers_are_jumpers no)
		(fp_line
			(start 0.7874 -0.4064)
			(end -0.7874 -0.4064)
			(stroke
				(width 0.1524)
				(type default)
			)
			(layer "B.SilkS")
		)
		(fp_line
			(start -0.7874 -0.4064)
			(end -0.7874 0.4064)
			(stroke
				(width 0.1524)
				(type default)
			)
			(layer "B.SilkS")
		)
		(fp_line
			(start 0.7874 0.4064)
			(end 0.7874 -0.4064)
			(stroke
				(width 0.1524)
				(type default)
			)
			(layer "B.SilkS")
		)
		(fp_line
			(start -0.7874 0.4064)
			(end 0.7874 0.4064)
			(stroke
				(width 0.1524)
				(type default)
			)
			(layer "B.SilkS")
		)
		(fp_line
			(start 0.67945 -0.305054)
			(end 0.12065 -0.305054)
			(stroke
				(width 0.1)
				(type default)
			)
			(layer "B.Fab")
		)
		(fp_line
			(start 0.12065 -0.305054)
			(end 0.12065 -0.2794)
			(stroke
				(width 0.1)
				(type default)
			)
			(layer "B.Fab")
		)
		(fp_line
			(start -0.12065 -0.3048)
			(end -0.67945 -0.3048)
			(stroke
				(width 0.1)
				(type default)
			)
			(layer "B.Fab")
		)
		(fp_line
			(start -0.67945 -0.3048)
			(end -0.67945 0.3048)
			(stroke
				(width 0.1)
				(type default)
			)
			(layer "B.Fab")
		)
		(fp_line
			(start 0.12065 -0.2794)
			(end -0.12065 -0.2794)
			(stroke
				(width 0.1)
				(type default)
			)
			(layer "B.Fab")
		)
		(fp_line
			(start -0.12065 -0.2794)
			(end -0.12065 -0.3048)
			(stroke
				(width 0.1)
				(type default)
			)
			(layer "B.Fab")
		)
		(fp_line
			(start 0.12065 0.2794)
			(end 0.12065 0.3048)
			(stroke
				(width 0.1)
				(type default)
			)
			(layer "B.Fab")
		)
		(fp_line
			(start -0.120396 0.2794)
			(end 0.12065 0.2794)
			(stroke
				(width 0.1)
				(type default)
			)
			(layer "B.Fab")
		)
		(fp_line
			(start 0.67945 0.3048)
			(end 0.67945 -0.305054)
			(stroke
				(width 0.1)
				(type default)
			)
			(layer "B.Fab")
		)
		(fp_line
			(start 0.12065 0.3048)
			(end 0.67945 0.3048)
			(stroke
				(width 0.1)
				(type default)
			)
			(layer "B.Fab")
		)
		(fp_line
			(start -0.120396 0.3048)
			(end -0.120396 0.2794)
			(stroke
				(width 0.1)
				(type default)
			)
			(layer "B.Fab")
		)
		(fp_line
			(start -0.67945 0.3048)
			(end -0.120396 0.3048)
			(stroke
				(width 0.1)
				(type default)
			)
			(layer "B.Fab")
		)
		(pad "1" smd circle
			(at 0.40005 0 270)
			(size 0 0)
			(layers "B.Cu" "B.Mask" "B.Paste")
			(net "I3C_SPD_DDRABCD_CPU1_LVC1_SCL_7")
		)
		(pad "2" smd circle
			(at -0.40005 0 270)
			(size 0 0)
			(layers "B.Cu" "B.Mask" "B.Paste")
			(net "I3C_SPD_DDRABCD_CPU1_LVC1_SCL")
		)
	)
	(footprint ""
		(layer "B.Cu")
		(at 352.68027 -59.737752)
		(property "Reference" "R498"
			(at 0 0 0)
			(layer "B.SilkS")
			(hide yes)
			(effects
				(font
					(size 1.27 1.27)
				)
				(justify mirror)
			)
		)
		(property "Value" ""
			(at 0 0 0)
			(layer "B.Fab")
			(effects
				(font
					(size 1.27 1.27)
				)
				(justify mirror)
			)
		)
		(duplicate_pad_numbers_are_jumpers no)
		(fp_line
			(start -0.7874 -0.4064)
			(end -0.7874 0.4064)
			(stroke
				(width 0.1524)
				(type default)
			)
			(layer "B.SilkS")
		)
		(fp_line
			(start -0.7874 0.4064)
			(end 0.7874 0.4064)
			(stroke
				(width 0.1524)
				(type default)
			)
			(layer "B.SilkS")
		)
		(fp_line
			(start 0.7874 -0.4064)
			(end -0.7874 -0.4064)
			(stroke
				(width 0.1524)
				(type default)
			)
			(layer "B.SilkS")
		)
		(fp_line
			(start 0.7874 0.4064)
			(end 0.7874 -0.4064)
			(stroke
				(width 0.1524)
				(type default)
			)
			(layer "B.SilkS")
		)
		(fp_line
			(start -0.67945 -0.3048)
			(end -0.67945 0.3048)
			(stroke
				(width 0.1)
				(type default)
			)
			(layer "B.Fab")
		)
		(fp_line
			(start -0.67945 0.3048)
			(end -0.120396 0.3048)
			(stroke
				(width 0.1)
				(type default)
			)
			(layer "B.Fab")
		)
		(fp_line
			(start -0.12065 -0.3048)
			(end -0.67945 -0.3048)
			(stroke
				(width 0.1)
				(type default)
			)
			(layer "B.Fab")
		)
		(fp_line
			(start -0.12065 -0.2794)
			(end -0.12065 -0.3048)
			(stroke
				(width 0.1)
				(type default)
			)
			(layer "B.Fab")
		)
		(fp_line
			(start -0.120396 0.2794)
			(end 0.12065 0.2794)
			(stroke
				(width 0.1)
				(type default)
			)
			(layer "B.Fab")
		)
		(fp_line
			(start -0.120396 0.3048)
			(end -0.120396 0.2794)
			(stroke
				(width 0.1)
				(type default)
			)
			(layer "B.Fab")
		)
		(fp_line
			(start 0.12065 -0.305054)
			(end 0.12065 -0.2794)
			(stroke
				(width 0.1)
				(type default)
			)
			(layer "B.Fab")
		)
		(fp_line
			(start 0.12065 -0.2794)
			(end -0.12065 -0.2794)
			(stroke
				(width 0.1)
				(type default)
			)
			(layer "B.Fab")
		)
		(fp_line
			(start 0.12065 0.2794)
			(end 0.12065 0.3048)
			(stroke
				(width 0.1)
				(type default)
			)
			(layer "B.Fab")
		)
		(fp_line
			(start 0.12065 0.3048)
			(end 0.67945 0.3048)
			(stroke
				(width 0.1)
				(type default)
			)
			(layer "B.Fab")
		)
		(fp_line
			(start 0.67945 -0.305054)
			(end 0.12065 -0.305054)
			(stroke
				(width 0.1)
				(type default)
			)
			(layer "B.Fab")
		)
		(fp_line
			(start 0.67945 0.3048)
			(end 0.67945 -0.305054)
			(stroke
				(width 0.1)
				(type default)
			)
			(layer "B.Fab")
		)
		(pad "1" smd circle
			(at 0.40005 0 180)
			(size 0 0)
			(layers "B.Cu" "B.Mask" "B.Paste")
			(net "P3V3_AUX")
		)
		(pad "2" smd circle
			(at -0.40005 0 180)
			(size 0 0)
			(layers "B.Cu" "B.Mask" "B.Paste")
			(net "FM_PCH_PRSNT_N")
		)
	)
	(footprint ""
		(layer "B.Cu")
		(at 131.93522 -24.895048 180)
		(property "Reference" "C2290"
			(at 0 0 0)
			(layer "B.SilkS")
			(hide yes)
			(effects
				(font
					(size 1.27 1.27)
				)
				(justify mirror)
			)
		)
		(property "Value" ""
			(at 0 0 0)
			(layer "B.Fab")
			(effects
				(font
					(size 1.27 1.27)
				)
				(justify mirror)
			)
		)
		(duplicate_pad_numbers_are_jumpers no)
		(fp_line
			(start 0.299974 0.150114)
			(end 0.299974 -0.150114)
			(stroke
				(width 0.1)
				(type default)
			)
			(layer "B.Fab")
		)
		(fp_line
			(start 0.299974 -0.150114)
			(end -0.299974 -0.150114)
			(stroke
				(width 0.1)
				(type default)
			)
			(layer "B.Fab")
		)
		(fp_line
			(start -0.299974 0.150114)
			(end 0.299974 0.150114)
			(stroke
				(width 0.1)
				(type default)
			)
			(layer "B.Fab")
		)
		(fp_line
			(start -0.299974 -0.150114)
			(end -0.299974 0.150114)
			(stroke
				(width 0.1)
				(type default)
			)
			(layer "B.Fab")
		)
		(pad "1" smd rect
			(at 0.2667 0)
			(size 0.3048 0.381)
			(layers "B.Cu" "B.Mask" "B.Paste")
			(net "USB3_PCH_TX_BUF_DN<4>")
		)
		(pad "2" smd rect
			(at -0.2667 0)
			(size 0.3048 0.381)
			(layers "B.Cu" "B.Mask" "B.Paste")
			(net "USB3_PCH_TX_BUF_C_DN<4>")
		)
	)
	(footprint ""
		(layer "B.Cu")
		(at 73.316084 -190.719456 -90)
		(property "Reference" "R559"
			(at 0 0 90)
			(layer "B.SilkS")
			(hide yes)
			(effects
				(font
					(size 1.27 1.27)
				)
				(justify mirror)
			)
		)
		(property "Value" ""
			(at 0 0 90)
			(layer "B.Fab")
			(effects
				(font
					(size 1.27 1.27)
				)
				(justify mirror)
			)
		)
		(duplicate_pad_numbers_are_jumpers no)
		(fp_line
			(start -0.7874 0.4064)
			(end 0.7874 0.4064)
			(stroke
				(width 0.1524)
				(type default)
			)
			(layer "B.SilkS")
		)
		(fp_line
			(start 0.7874 0.4064)
			(end 0.7874 -0.4064)
			(stroke
				(width 0.1524)
				(type default)
			)
			(layer "B.SilkS")
		)
		(fp_line
			(start -0.7874 -0.4064)
			(end -0.7874 0.4064)
			(stroke
				(width 0.1524)
				(type default)
			)
			(layer "B.SilkS")
		)
		(fp_line
			(start 0.7874 -0.4064)
			(end -0.7874 -0.4064)
			(stroke
				(width 0.1524)
				(type default)
			)
			(layer "B.SilkS")
		)
		(fp_line
			(start -0.67945 0.3048)
			(end -0.120396 0.3048)
			(stroke
				(width 0.1)
				(type default)
			)
			(layer "B.Fab")
		)
		(fp_line
			(start -0.120396 0.3048)
			(end -0.120396 0.2794)
			(stroke
				(width 0.1)
				(type default)
			)
			(layer "B.Fab")
		)
		(fp_line
			(start 0.12065 0.3048)
			(end 0.67945 0.3048)
			(stroke
				(width 0.1)
				(type default)
			)
			(layer "B.Fab")
		)
		(fp_line
			(start 0.67945 0.3048)
			(end 0.67945 -0.305054)
			(stroke
				(width 0.1)
				(type default)
			)
			(layer "B.Fab")
		)
		(fp_line
			(start -0.120396 0.2794)
			(end 0.12065 0.2794)
			(stroke
				(width 0.1)
				(type default)
			)
			(layer "B.Fab")
		)
		(fp_line
			(start 0.12065 0.2794)
			(end 0.12065 0.3048)
			(stroke
				(width 0.1)
				(type default)
			)
			(layer "B.Fab")
		)
		(fp_line
			(start -0.12065 -0.2794)
			(end -0.12065 -0.3048)
			(stroke
				(width 0.1)
				(type default)
			)
			(layer "B.Fab")
		)
		(fp_line
			(start 0.12065 -0.2794)
			(end -0.12065 -0.2794)
			(stroke
				(width 0.1)
				(type default)
			)
			(layer "B.Fab")
		)
		(fp_line
			(start -0.67945 -0.3048)
			(end -0.67945 0.3048)
			(stroke
				(width 0.1)
				(type default)
			)
			(layer "B.Fab")
		)
		(fp_line
			(start -0.12065 -0.3048)
			(end -0.67945 -0.3048)
			(stroke
				(width 0.1)
				(type default)
			)
			(layer "B.Fab")
		)
		(fp_line
			(start 0.12065 -0.305054)
			(end 0.12065 -0.2794)
			(stroke
				(width 0.1)
				(type default)
			)
			(layer "B.Fab")
		)
		(fp_line
			(start 0.67945 -0.305054)
			(end 0.12065 -0.305054)
			(stroke
				(width 0.1)
				(type default)
			)
			(layer "B.Fab")
		)
		(pad "1" smd circle
			(at 0.40005 0 90)
			(size 0 0)
			(layers "B.Cu" "B.Mask" "B.Paste")
			(net "SVID_DIO1_CPU1_R")
		)
		(pad "2" smd circle
			(at -0.40005 0 90)
			(size 0 0)
			(layers "B.Cu" "B.Mask" "B.Paste")
			(net "PVNN_TERM_CPU1")
		)
	)
)
